A
A
B
B
C
C
D
D
E
E
1
1
2
2
3
3
4
4
Drill Drawing View (Scale 2:1)
REV
X1
DESCRIPTION
INITIAL RELEASE
DATE
01/24/2023
APPROVED
INTERPRET THIS DRAWING IN ACCORDANCE WITH IPC-D-325A.
1.
BOARD FABRICATION AND QUALITY PER IPC-6012, CLASS 2, EXCEPT SPECIFIED HEREIN.
2.
MUST COMPLY WITH EUROPEAN DIRECTIVE 2002/95/EC (RoHS).
3.
DIMENSIONAL LIMITS APPLY AFTER PLATING OR COATING.
4.
BOW AND TWIST MAXIMUM IS 0.75%.
5.
MATERIAL: LAMINATE AND PREPREG SHALL BE IN ACCORDANCE WITH IPC-4101/21. 170 
DEGREES CELSIUS MINIMUM Tg, UL 94V-0.
6.
STACKUP SUMMARY: 
     A. NUMBER OF COPPER LAYERS: 4
     B. BOARD THICKNESS SHALL BE 1.6mm +/- 10%
     C. COPPER: See Layer Stack 
     D. DEFAULT TRACE/SPACE: 0.2mm/0.2mm
     E. CONDUCTOR WIDTH TOLERANCE = +/- 0.01mm
7.
ALL VIAS TO BE TENTED BY SOLDERMASK
8.
SURFACE FINISH/PLATING:
     A. BOARD SHALL BE IMMERSION GOLD PLATED (ENIG) ACCORDING TO IPC-4552. 
THICKNESS SHALL BE A MINIMUM OF 0.05μm GOLD OVER 3-6μm NICKEL.
9.
SOLDERMASK WITH LIQUID PHOTO IMAGEABLE (LPI) PER IPC-SM-840C, CLASS T. 
COLOR: BLACK
10.
SILKSCREEN PER SUPPLIED ARTWORK WITH ORGANIC, NON-CONDUCTIVE, EPOXY INK. 
SILKSCREEN MAY BE TRIMMED OFF ANY SOLDERABLE ENTITY.
COLOR: WHITE
11.
100% BARE BOARD ELECTRICAL TEST TO BE DONE WITH REFERENCE TO SUPPLIED 
NETLIST.
12.
LOCATE MANUFACTURER'S IDENTIFICATION AND LOT CODE ON PRIMARY SIDE FREE 
FROM ALL METAL ENTITY RENDERED IN SILKSCREEN. 
13.
CONTROLLED IMPEDANCE REQUIRED ON BOARD.
SEE TABLE 1: SINGLE ENDED CONTROLLED IMPEDANCE
14.
NOTES: UNITS IN MILLIMETERS UNLESS OTHERWISE SPECIFIED
Layer
Thickness
Top Overlay
Top Solder
0.018mm
L01-Top Layer
0.071mm
0.117mm
L02-Inner Layer
0.036mm
1.123mm
L03-Inner Layer
0.036mm
0.117mm
L04-Bottom Layer
0.071mm
Bottom Solder
0.018mm
Bottom Overlay
Total thickness: 1.606mm
Layer Stack Legend
Trace layer
L01-Top Layer
L04-Bottom Layer
Reference layers
L02-Inner Layer
L03-Inner Layer
Target Impedance
50
50
Wide Trace Width
0.19mm
0.19mm
Target Tolerance
10%
10%
TABLE1: SINGLE ENDED CONTROLLED IMPEDANCE
Symbol
Count
84
10
9
2
4
109 Total
Hole Size
0.300mm
1.090mm
1.200mm
3.000mm
3.700mm
Plated
Plated
Plated
Plated
Non-Plated
Plated
Drill Layer Pair
L01-Top Layer - L04-Bottom Layer
L01-Top Layer - L04-Bottom Layer
L01-Top Layer - L04-Bottom Layer
L01-Top Layer - L04-Bottom Layer
L01-Top Layer - L04-Bottom Layer
Via / Pad
Via
Pad
Pad
Pad
Pad
Hole Tolerance
+0.000mm/-0.300mm
+/-0.076mm
+/-0.075mm
+/-0.051mm
+/-0.075mm
Drill Table
50.80mm
50.80mm
